(kicad_pcb
	(version 20260206)
	(generator "pcbnew")
	(generator_version "10.0")
	(general
		(thickness 1.6)
		(legacy_teardrops no)
	)
	(paper "A4")
	(title_block
		(title "peb — Lightning_PEB_BRD.brd")
		(comment 1 "Lightning (Wiwynn / Facebook NVMe JBOF) / footprints 2076-2084 of 2563")
	)
	(layers
		(0 "F.Cu" signal "TOP")
		(4 "In1.Cu" signal "L2GND")
		(6 "In2.Cu" signal "L3")
		(8 "In3.Cu" signal "L4VCC")
		(10 "In4.Cu" signal "L5VCC")
		(12 "In5.Cu" signal "L6")
		(14 "In6.Cu" signal "L7GND")
		(2 "B.Cu" signal "BOTTOM")
		(9 "F.Adhes" user "F.Adhesive")
		(11 "B.Adhes" user "B.Adhesive")
		(13 "F.Paste" user "Package Geometry/Pastemask Top")
		(15 "B.Paste" user "Package Geometry/Pastemask Bottom")
		(5 "F.SilkS" user "Ref Des/Silkscreen Top")
		(7 "B.SilkS" user "Ref Des/Silkscreen Bottom")
		(1 "F.Mask" user "Board Geometry/Soldermask Top")
		(3 "B.Mask" user "Board Geometry/Soldermask Bottom")
		(17 "Dwgs.User" user "User.Drawings")
		(19 "Cmts.User" user "User.Comments")
		(21 "Eco1.User" user "User.Eco1")
		(23 "Eco2.User" user "User.Eco2")
		(25 "Edge.Cuts" user "Board Geometry/Outline")
		(27 "Margin" user)
		(31 "F.CrtYd" user "Package Geometry/Place Bound Top")
		(29 "B.CrtYd" user "Package Geometry/Place Bound Bottom")
		(35 "F.Fab" user "Ref Des/Assembly Top")
		(33 "B.Fab" user "Ref Des/Assembly Bottom")
	)
	(footprint ""
		(layer "B.Cu")
		(at 72.747124 -183.235092)
		(property "Reference" "R4103"
			(at 0 0 0)
			(layer "B.SilkS")
			(hide yes)
			(effects
				(font
					(size 1.27 1.27)
				)
				(justify mirror)
			)
		)
		(property "Value" "4K7R2F-GP"
			(at -0.064008 -3.993896 0)
			(unlocked yes)
			(layer "B.Fab")
			(hide yes)
			(effects
				(font
					(size 1.016 1.016)
					(thickness 0.1524)
				)
				(justify mirror)
			)
		)
		(property "Device Type" "R402H16"
			(at -0.064008 -5.517896 0)
			(unlocked yes)
			(layer "B.Fab")
			(hide yes)
			(effects
				(font
					(size 1.016 1.016)
					(thickness 0.1524)
				)
				(justify mirror)
			)
		)
		(duplicate_pad_numbers_are_jumpers no)
		(fp_line
			(start -0.508 -0.9398)
			(end 0.508 -0.9398)
			(stroke
				(width 0.1524)
				(type default)
			)
			(layer "B.SilkS")
		)
		(fp_line
			(start 0.508 -0.9398)
			(end 0.508 0.9398)
			(stroke
				(width 0.1524)
				(type default)
			)
			(layer "B.SilkS")
		)
		(fp_rect
			(start 0.508 0.9398)
			(end -0.508 -0.9398)
			(stroke
				(width 0)
				(type default)
			)
			(fill no)
			(layer "B.CrtYd")
		)
		(fp_rect
			(start 0.508 0.9398)
			(end -0.508 -0.9398)
			(stroke
				(width 0)
				(type default)
			)
			(fill no)
			(layer "B.Fab")
		)
		(pad "1" smd custom
			(at 0 -0.4445 180)
			(size 0.1397 0.1397)
			(layers "B.Cu" "B.Mask" "B.Paste")
			(net "SSD_ATNLED#0")
			(options
				(clearance outline)
				(anchor circle)
			)
			(primitives
				(gr_poly
					(pts
						(arc
							(start -0.1778 0.2794)
							(mid -0.249642 0.249642)
							(end -0.2794 0.1778)
						)
						(arc
							(start -0.2794 -0.1778)
							(mid -0.249642 -0.249642)
							(end -0.1778 -0.2794)
						)
						(arc
							(start 0.1778 -0.2794)
							(mid 0.249642 -0.249642)
							(end 0.2794 -0.1778)
						)
						(arc
							(start 0.2794 0.1778)
							(mid 0.249642 0.249642)
							(end 0.1778 0.2794)
						)
					)
					(width 0)
					(fill yes)
				)
			)
		)
		(pad "2" smd custom
			(at 0 0.4445 180)
			(size 0.1397 0.1397)
			(layers "B.Cu" "B.Mask" "B.Paste")
			(net "P3V3_STBY")
			(options
				(clearance outline)
				(anchor circle)
			)
			(primitives
				(gr_poly
					(pts
						(arc
							(start -0.1778 0.2794)
							(mid -0.249642 0.249642)
							(end -0.2794 0.1778)
						)
						(arc
							(start -0.2794 -0.1778)
							(mid -0.249642 -0.249642)
							(end -0.1778 -0.2794)
						)
						(arc
							(start 0.1778 -0.2794)
							(mid 0.249642 -0.249642)
							(end 0.2794 -0.1778)
						)
						(arc
							(start 0.2794 0.1778)
							(mid 0.249642 0.249642)
							(end 0.1778 0.2794)
						)
					)
					(width 0)
					(fill yes)
				)
			)
		)
	)
	(footprint ""
		(layer "B.Cu")
		(at 235.966 -20.447)
		(property "Reference" "R813"
			(at 0 0 0)
			(layer "B.SilkS")
			(hide yes)
			(effects
				(font
					(size 1.27 1.27)
				)
				(justify mirror)
			)
		)
		(property "Value" "4K7R2F-GP"
			(at -0.064008 -3.993896 0)
			(unlocked yes)
			(layer "B.Fab")
			(hide yes)
			(effects
				(font
					(size 1.016 1.016)
					(thickness 0.1524)
				)
				(justify mirror)
			)
		)
		(property "Device Type" "R402H16"
			(at -0.064008 -5.517896 0)
			(unlocked yes)
			(layer "B.Fab")
			(hide yes)
			(effects
				(font
					(size 1.016 1.016)
					(thickness 0.1524)
				)
				(justify mirror)
			)
		)
		(duplicate_pad_numbers_are_jumpers no)
		(fp_line
			(start -0.508 -0.9398)
			(end 0.508 -0.9398)
			(stroke
				(width 0.1524)
				(type default)
			)
			(layer "B.SilkS")
		)
		(fp_line
			(start 0.508 -0.9398)
			(end 0.508 0.9398)
			(stroke
				(width 0.1524)
				(type default)
			)
			(layer "B.SilkS")
		)
		(fp_rect
			(start 0.508 0.9398)
			(end -0.508 -0.9398)
			(stroke
				(width 0)
				(type default)
			)
			(fill no)
			(layer "B.CrtYd")
		)
		(fp_rect
			(start 0.508 0.9398)
			(end -0.508 -0.9398)
			(stroke
				(width 0)
				(type default)
			)
			(fill no)
			(layer "B.Fab")
		)
		(pad "1" smd custom
			(at 0 -0.4445 180)
			(size 0.1397 0.1397)
			(layers "B.Cu" "B.Mask" "B.Paste")
			(net "BOOTSTRAP6")
			(options
				(clearance outline)
				(anchor circle)
			)
			(primitives
				(gr_poly
					(pts
						(arc
							(start -0.1778 0.2794)
							(mid -0.249642 0.249642)
							(end -0.2794 0.1778)
						)
						(arc
							(start -0.2794 -0.1778)
							(mid -0.249642 -0.249642)
							(end -0.1778 -0.2794)
						)
						(arc
							(start 0.1778 -0.2794)
							(mid 0.249642 -0.249642)
							(end 0.2794 -0.1778)
						)
						(arc
							(start 0.2794 0.1778)
							(mid 0.249642 0.249642)
							(end 0.1778 0.2794)
						)
					)
					(width 0)
					(fill yes)
				)
			)
		)
		(pad "2" smd custom
			(at 0 0.4445 180)
			(size 0.1397 0.1397)
			(layers "B.Cu" "B.Mask" "B.Paste")
			(net "DUT_VDDO")
			(options
				(clearance outline)
				(anchor circle)
			)
			(primitives
				(gr_poly
					(pts
						(arc
							(start -0.1778 0.2794)
							(mid -0.249642 0.249642)
							(end -0.2794 0.1778)
						)
						(arc
							(start -0.2794 -0.1778)
							(mid -0.249642 -0.249642)
							(end -0.1778 -0.2794)
						)
						(arc
							(start 0.1778 -0.2794)
							(mid 0.249642 -0.249642)
							(end 0.2794 -0.1778)
						)
						(arc
							(start 0.2794 0.1778)
							(mid 0.249642 0.249642)
							(end 0.1778 0.2794)
						)
					)
					(width 0)
					(fill yes)
				)
			)
		)
	)
	(footprint ""
		(layer "B.Cu")
		(at 265.9253 -8.85571 180)
		(property "Reference" "R2966"
			(at 0 0 0)
			(layer "B.SilkS")
			(hide yes)
			(effects
				(font
					(size 1.27 1.27)
				)
				(justify mirror)
			)
		)
		(property "Value" "0R2J-2-GP"
			(at -0.064008 -3.993896 180)
			(unlocked yes)
			(layer "B.Fab")
			(hide yes)
			(effects
				(font
					(size 1.016 1.016)
					(thickness 0.1524)
				)
				(justify mirror)
			)
		)
		(property "Device Type" "R402H16"
			(at -0.064008 -5.517896 180)
			(unlocked yes)
			(layer "B.Fab")
			(hide yes)
			(effects
				(font
					(size 1.016 1.016)
					(thickness 0.1524)
				)
				(justify mirror)
			)
		)
		(duplicate_pad_numbers_are_jumpers no)
		(fp_line
			(start 0.508 -0.9398)
			(end 0.508 0.9398)
			(stroke
				(width 0.1524)
				(type default)
			)
			(layer "B.SilkS")
		)
		(fp_line
			(start -0.508 -0.9398)
			(end 0.508 -0.9398)
			(stroke
				(width 0.1524)
				(type default)
			)
			(layer "B.SilkS")
		)
		(fp_rect
			(start 0.508 0.9398)
			(end -0.508 -0.9398)
			(stroke
				(width 0)
				(type default)
			)
			(fill no)
			(layer "B.CrtYd")
		)
		(fp_rect
			(start 0.508 0.9398)
			(end -0.508 -0.9398)
			(stroke
				(width 0)
				(type default)
			)
			(fill no)
			(layer "B.Fab")
		)
		(pad "1" smd custom
			(at 0 -0.4445)
			(size 0.1397 0.1397)
			(layers "B.Cu" "B.Mask" "B.Paste")
			(net "HOST7_RST_N")
			(options
				(clearance outline)
				(anchor circle)
			)
			(primitives
				(gr_poly
					(pts
						(arc
							(start -0.1778 0.2794)
							(mid -0.249642 0.249642)
							(end -0.2794 0.1778)
						)
						(arc
							(start -0.2794 -0.1778)
							(mid -0.249642 -0.249642)
							(end -0.1778 -0.2794)
						)
						(arc
							(start 0.1778 -0.2794)
							(mid 0.249642 -0.249642)
							(end 0.2794 -0.1778)
						)
						(arc
							(start 0.2794 0.1778)
							(mid 0.249642 0.249642)
							(end 0.1778 0.2794)
						)
					)
					(width 0)
					(fill yes)
				)
			)
		)
		(pad "2" smd custom
			(at 0 0.4445)
			(size 0.1397 0.1397)
			(layers "B.Cu" "B.Mask" "B.Paste")
			(net "HOST7_RST_N_C")
			(options
				(clearance outline)
				(anchor circle)
			)
			(primitives
				(gr_poly
					(pts
						(arc
							(start -0.1778 0.2794)
							(mid -0.249642 0.249642)
							(end -0.2794 0.1778)
						)
						(arc
							(start -0.2794 -0.1778)
							(mid -0.249642 -0.249642)
							(end -0.1778 -0.2794)
						)
						(arc
							(start 0.1778 -0.2794)
							(mid 0.249642 -0.249642)
							(end 0.2794 -0.1778)
						)
						(arc
							(start 0.2794 0.1778)
							(mid 0.249642 0.249642)
							(end 0.1778 0.2794)
						)
					)
					(width 0)
					(fill yes)
				)
			)
		)
	)
	(footprint ""
		(layer "B.Cu")
		(at 236.609128 -31.9786)
		(property "Reference" "C475"
			(at 0 0 0)
			(layer "B.SilkS")
			(hide yes)
			(effects
				(font
					(size 1.27 1.27)
				)
				(justify mirror)
			)
		)
		(property "Value" "SCD1U16V1KX-1-GP"
			(at 2.8321 -1.7399 0)
			(unlocked yes)
			(layer "B.Fab")
			(hide yes)
			(effects
				(font
					(size 1.016 1.016)
					(thickness 0.1524)
				)
				(justify mirror)
			)
		)
		(property "Device Type" "C0201H13"
			(at 2.8321 -3.2639 0)
			(unlocked yes)
			(layer "B.Fab")
			(hide yes)
			(effects
				(font
					(size 1.016 1.016)
					(thickness 0.1524)
				)
				(justify mirror)
			)
		)
		(duplicate_pad_numbers_are_jumpers no)
		(fp_rect
			(start 0.2794 0.6477)
			(end -0.2794 -0.6477)
			(stroke
				(width 0)
				(type default)
			)
			(fill no)
			(layer "B.CrtYd")
		)
		(fp_rect
			(start 0.2794 0.6477)
			(end -0.2794 -0.6477)
			(stroke
				(width 0)
				(type default)
			)
			(fill no)
			(layer "B.Fab")
		)
		(pad "1" smd custom
			(at 0 -0.2794 180)
			(size 0.0762 0.0762)
			(layers "B.Cu" "B.Mask" "B.Paste")
			(net "DUT_VDDO")
			(options
				(clearance outline)
				(anchor circle)
			)
			(primitives
				(gr_poly
					(pts
						(arc
							(start 0.1524 0.127)
							(mid 0.137521 0.162921)
							(end 0.1016 0.1778)
						)
						(arc
							(start -0.1016 0.1778)
							(mid -0.137521 0.162921)
							(end -0.1524 0.127)
						)
						(arc
							(start -0.1524 -0.127)
							(mid -0.137521 -0.162921)
							(end -0.1016 -0.1778)
						)
						(arc
							(start 0.1016 -0.1778)
							(mid 0.137521 -0.162921)
							(end 0.1524 -0.127)
						)
					)
					(width 0)
					(fill yes)
				)
			)
		)
		(pad "2" smd custom
			(at 0 0.2794 180)
			(size 0.0762 0.0762)
			(layers "B.Cu" "B.Mask" "B.Paste")
			(net "GND")
			(options
				(clearance outline)
				(anchor circle)
			)
			(primitives
				(gr_poly
					(pts
						(arc
							(start 0.1524 0.127)
							(mid 0.137521 0.162921)
							(end 0.1016 0.1778)
						)
						(arc
							(start -0.1016 0.1778)
							(mid -0.137521 0.162921)
							(end -0.1524 0.127)
						)
						(arc
							(start -0.1524 -0.127)
							(mid -0.137521 -0.162921)
							(end -0.1016 -0.1778)
						)
						(arc
							(start 0.1016 -0.1778)
							(mid 0.137521 -0.162921)
							(end 0.1524 -0.127)
						)
					)
					(width 0)
					(fill yes)
				)
			)
		)
	)
	(footprint ""
		(layer "B.Cu")
		(at 310.007 -60.833 180)
		(property "Reference" "PG63"
			(at 0 0 0)
			(layer "B.SilkS")
			(hide yes)
			(effects
				(font
					(size 1.27 1.27)
				)
				(justify mirror)
			)
		)
		(property "Value" "GAP-CLOSE-PWR-3-GP"
			(at -0.0254 -6.5786 180)
			(unlocked yes)
			(layer "B.Fab")
			(hide yes)
			(effects
				(font
					(size 1.016 1.016)
					(thickness 0.1524)
				)
				(justify mirror)
			)
		)
		(property "Device Type" "GAP-CLOSE-PWR-3"
			(at -0.0254 -8.255 180)
			(unlocked yes)
			(layer "B.Fab")
			(hide yes)
			(effects
				(font
					(size 1.016 1.016)
					(thickness 0.1524)
				)
				(justify mirror)
			)
		)
		(duplicate_pad_numbers_are_jumpers no)
		(fp_rect
			(start 0.7112 0.4572)
			(end -0.7112 -0.4572)
			(stroke
				(width 0)
				(type default)
			)
			(fill no)
			(layer "B.CrtYd")
		)
		(fp_poly
			(pts
				(xy 0.7112 -0.4572) (xy -0.7112 -0.4572) (xy -0.7112 0.4572) (xy 0.7112 0.4572)
			)
			(stroke
				(width 0)
				(type default)
			)
			(fill no)
			(layer "B.Fab")
		)
		(pad "1" smd rect
			(at 0.3048 0)
			(size 0.6604 0.762)
			(layers "B.Cu" "B.Mask" "B.Paste")
			(net "DUT_VDD")
		)
		(pad "2" smd rect
			(at -0.3048 0)
			(size 0.6604 0.762)
			(layers "B.Cu" "B.Mask" "B.Paste")
			(net "P0V9_E")
		)
	)
	(footprint ""
		(layer "B.Cu")
		(at 229.60838 -39.999412)
		(property "Reference" "TP268"
			(at 0 0 0)
			(layer "B.SilkS")
			(hide yes)
			(effects
				(font
					(size 1.27 1.27)
				)
				(justify mirror)
			)
		)
		(property "Value" "TPAD28-2-GP"
			(at 0.0127 -1.6637 0)
			(unlocked yes)
			(layer "B.Fab")
			(hide yes)
			(effects
				(font
					(size 1.016 1.016)
					(thickness 0.1524)
				)
				(justify mirror)
			)
		)
		(property "Device Type" "TPAD28"
			(at 0.0127 -3.1877 0)
			(unlocked yes)
			(layer "B.Fab")
			(hide yes)
			(effects
				(font
					(size 1.016 1.016)
					(thickness 0.1524)
				)
				(justify mirror)
			)
		)
		(duplicate_pad_numbers_are_jumpers no)
		(fp_poly
			(pts
				(arc
					(start 0.3556 0)
					(mid -0.3556 0)
					(end 0.3556 0)
				)
			)
			(stroke
				(width 0)
				(type default)
			)
			(fill no)
			(layer "B.CrtYd")
		)
		(fp_poly
			(pts
				(arc
					(start 0.6096 0)
					(mid -0.6096 0)
					(end 0.6096 0)
				)
			)
			(stroke
				(width 0)
				(type default)
			)
			(fill no)
			(layer "B.Fab")
		)
		(pad "1" smd circle
			(at 0 0 180)
			(size 0.7112 0.7112)
			(layers "B.Cu" "B.Mask" "B.Paste")
			(net "LBI_DATA_9")
		)
	)
	(footprint ""
		(layer "B.Cu")
		(at 174.031402 -62.714632)
		(property "Reference" "PC194"
			(at 0 0 0)
			(layer "B.SilkS")
			(hide yes)
			(effects
				(font
					(size 1.27 1.27)
				)
				(justify mirror)
			)
		)
		(property "Value" "SC22U6D3V5MX-5-GP"
			(at 0.0762 -6.1214 0)
			(unlocked yes)
			(layer "B.Fab")
			(hide yes)
			(effects
				(font
					(size 1.016 1.016)
					(thickness 0.1524)
				)
				(justify mirror)
			)
		)
		(property "Device Type" "C805H56"
			(at 0.0762 -8.1534 0)
			(unlocked yes)
			(layer "B.Fab")
			(hide yes)
			(effects
				(font
					(size 1.016 1.016)
					(thickness 0.1524)
				)
				(justify mirror)
			)
		)
		(duplicate_pad_numbers_are_jumpers no)
		(fp_line
			(start -0.635 0)
			(end 0.635 0)
			(stroke
				(width 0.508)
				(type default)
			)
			(layer "B.SilkS")
		)
		(fp_rect
			(start 0.9652 1.778)
			(end -0.9652 -1.778)
			(stroke
				(width 0)
				(type default)
			)
			(fill no)
			(layer "B.CrtYd")
		)
		(fp_poly
			(pts
				(xy 0.9652 -1.778) (xy -0.9652 -1.778) (xy -0.9652 1.778) (xy 0.9652 1.778)
			)
			(stroke
				(width 0)
				(type default)
			)
			(fill no)
			(layer "B.Fab")
		)
		(pad "1" smd rect
			(at 0 -0.9652 180)
			(size 1.397 1.143)
			(layers "B.Cu" "B.Mask" "B.Paste")
			(net "P0V9")
		)
		(pad "2" smd rect
			(at 0 0.9652 180)
			(size 1.397 1.143)
			(layers "B.Cu" "B.Mask" "B.Paste")
			(net "GND")
		)
	)
	(footprint ""
		(layer "B.Cu")
		(at 35.248088 -128.388618 90)
		(property "Reference" "C209"
			(at 0 0 90)
			(layer "B.SilkS")
			(hide yes)
			(effects
				(font
					(size 1.27 1.27)
				)
				(justify mirror)
			)
		)
		(property "Value" "SC220P50V2KX-3GP"
			(at -1.1811 -2.7051 90)
			(unlocked yes)
			(layer "B.Fab")
			(hide yes)
			(effects
				(font
					(size 1.016 1.016)
					(thickness 0.1524)
				)
				(justify mirror)
			)
		)
		(property "Device Type" "C402H22"
			(at -1.1811 -4.2291 90)
			(unlocked yes)
			(layer "B.Fab")
			(hide yes)
			(effects
				(font
					(size 1.016 1.016)
					(thickness 0.1524)
				)
				(justify mirror)
			)
		)
		(duplicate_pad_numbers_are_jumpers no)
		(fp_rect
			(start 0.4318 0.9525)
			(end -0.4318 -0.9525)
			(stroke
				(width 0)
				(type default)
			)
			(fill no)
			(layer "B.CrtYd")
		)
		(fp_rect
			(start 0.4318 0.9525)
			(end -0.4318 -0.9525)
			(stroke
				(width 0)
				(type default)
			)
			(fill no)
			(layer "B.Fab")
		)
		(pad "1" smd custom
			(at 0 -0.4445 270)
			(size 0.1524 0.1524)
			(layers "B.Cu" "B.Mask" "B.Paste")
			(net "P3V3_STBY")
			(options
				(clearance outline)
				(anchor circle)
			)
			(primitives
				(gr_poly
					(pts
						(arc
							(start 0.3048 0.2032)
							(mid 0.275042 0.275042)
							(end 0.2032 0.3048)
						)
						(arc
							(start -0.2032 0.3048)
							(mid -0.275042 0.275042)
							(end -0.3048 0.2032)
						)
						(arc
							(start -0.3048 -0.2032)
							(mid -0.275042 -0.275042)
							(end -0.2032 -0.3048)
						)
						(arc
							(start 0.2032 -0.3048)
							(mid 0.275042 -0.275042)
							(end 0.3048 -0.2032)
						)
					)
					(width 0)
					(fill yes)
				)
			)
		)
		(pad "2" smd custom
			(at 0 0.4445 270)
			(size 0.1524 0.1524)
			(layers "B.Cu" "B.Mask" "B.Paste")
			(net "GND")
			(options
				(clearance outline)
				(anchor circle)
			)
			(primitives
				(gr_poly
					(pts
						(arc
							(start 0.3048 0.2032)
							(mid 0.275042 0.275042)
							(end 0.2032 0.3048)
						)
						(arc
							(start -0.2032 0.3048)
							(mid -0.275042 0.275042)
							(end -0.3048 0.2032)
						)
						(arc
							(start -0.3048 -0.2032)
							(mid -0.275042 -0.275042)
							(end -0.2032 -0.3048)
						)
						(arc
							(start 0.2032 -0.3048)
							(mid 0.275042 -0.275042)
							(end 0.3048 -0.2032)
						)
					)
					(width 0)
					(fill yes)
				)
			)
		)
	)
	(footprint ""
		(layer "B.Cu")
		(at 78.023212 -192.641474)
		(property "Reference" "R3217"
			(at 0 0 0)
			(layer "B.SilkS")
			(hide yes)
			(effects
				(font
					(size 1.27 1.27)
				)
				(justify mirror)
			)
		)
		(property "Value" "0R2J-2-GP"
			(at -0.064008 -3.993896 0)
			(unlocked yes)
			(layer "B.Fab")
			(hide yes)
			(effects
				(font
					(size 1.016 1.016)
					(thickness 0.1524)
				)
				(justify mirror)
			)
		)
		(property "Device Type" "R402H16"
			(at -0.064008 -5.517896 0)
			(unlocked yes)
			(layer "B.Fab")
			(hide yes)
			(effects
				(font
					(size 1.016 1.016)
					(thickness 0.1524)
				)
				(justify mirror)
			)
		)
		(duplicate_pad_numbers_are_jumpers no)
		(fp_line
			(start -0.508 -0.9398)
			(end 0.508 -0.9398)
			(stroke
				(width 0.1524)
				(type default)
			)
			(layer "B.SilkS")
		)
		(fp_line
			(start 0.508 -0.9398)
			(end 0.508 0.9398)
			(stroke
				(width 0.1524)
				(type default)
			)
			(layer "B.SilkS")
		)
		(fp_rect
			(start 0.508 0.9398)
			(end -0.508 -0.9398)
			(stroke
				(width 0)
				(type default)
			)
			(fill no)
			(layer "B.CrtYd")
		)
		(fp_rect
			(start 0.508 0.9398)
			(end -0.508 -0.9398)
			(stroke
				(width 0)
				(type default)
			)
			(fill no)
			(layer "B.Fab")
		)
		(pad "1" smd custom
			(at 0 -0.4445 180)
			(size 0.1397 0.1397)
			(layers "B.Cu" "B.Mask" "B.Paste")
			(net "BMC_SSD_RST#5")
			(options
				(clearance outline)
				(anchor circle)
			)
			(primitives
				(gr_poly
					(pts
						(arc
							(start -0.1778 0.2794)
							(mid -0.249642 0.249642)
							(end -0.2794 0.1778)
						)
						(arc
							(start -0.2794 -0.1778)
							(mid -0.249642 -0.249642)
							(end -0.1778 -0.2794)
						)
						(arc
							(start 0.1778 -0.2794)
							(mid 0.249642 -0.249642)
							(end 0.2794 -0.1778)
						)
						(arc
							(start 0.2794 0.1778)
							(mid 0.249642 0.249642)
							(end 0.1778 0.2794)
						)
					)
					(width 0)
					(fill yes)
				)
			)
		)
		(pad "2" smd custom
			(at 0 0.4445 180)
			(size 0.1397 0.1397)
			(layers "B.Cu" "B.Mask" "B.Paste")
			(net "BMC_SSD_RST#0_A5")
			(options
				(clearance outline)
				(anchor circle)
			)
			(primitives
				(gr_poly
					(pts
						(arc
							(start -0.1778 0.2794)
							(mid -0.249642 0.249642)
							(end -0.2794 0.1778)
						)
						(arc
							(start -0.2794 -0.1778)
							(mid -0.249642 -0.249642)
							(end -0.1778 -0.2794)
						)
						(arc
							(start 0.1778 -0.2794)
							(mid 0.249642 -0.249642)
							(end 0.2794 -0.1778)
						)
						(arc
							(start 0.2794 0.1778)
							(mid 0.249642 0.249642)
							(end 0.1778 0.2794)
						)
					)
					(width 0)
					(fill yes)
				)
			)
		)
	)
)
